(kicad_pcb
	(version 20260206)
	(generator "pcbnew")
	(generator_version "10.0")
	(general
		(thickness 1.6)
		(legacy_teardrops no)
	)
	(paper "A4")
	(title_block
		(title "03242023_DA0F0TMBIJ0_F0T_Motherboard_J_brd_V01_OCP.brd")
		(comment 1 "Grand Teton / footprints 4349-4354 of 6105")
	)
	(layers
		(0 "F.Cu" signal "TOP")
		(4 "In1.Cu" signal "GND")
		(6 "In2.Cu" signal "IN1")
		(8 "In3.Cu" signal "GND1")
		(10 "In4.Cu" signal "IN2")
		(12 "In5.Cu" signal "GND2")
		(14 "In6.Cu" signal "IN3")
		(16 "In7.Cu" signal "GND3")
		(18 "In8.Cu" signal "VCC")
		(20 "In9.Cu" signal "VCC1")
		(22 "In10.Cu" signal "GND4")
		(24 "In11.Cu" signal "IN4")
		(26 "In12.Cu" signal "GND5")
		(28 "In13.Cu" signal "IN5")
		(30 "In14.Cu" signal "GND6")
		(32 "In15.Cu" signal "IN6")
		(34 "In16.Cu" signal "GND7")
		(2 "B.Cu" signal "BOTTOM")
		(9 "F.Adhes" user "F.Adhesive")
		(11 "B.Adhes" user "B.Adhesive")
		(13 "F.Paste" user "Package Geometry/Pastemask Top")
		(15 "B.Paste" user "Package Geometry/Pastemask Bottom")
		(5 "F.SilkS" user "Ref Des/Silkscreen Top")
		(7 "B.SilkS" user "Ref Des/Silkscreen Bottom")
		(1 "F.Mask" user "Board Geometry/Soldermask Top")
		(3 "B.Mask" user "Board Geometry/Soldermask Bottom")
		(17 "Dwgs.User" user "User.Drawings")
		(19 "Cmts.User" user "User.Comments")
		(21 "Eco1.User" user "User.Eco1")
		(23 "Eco2.User" user "User.Eco2")
		(25 "Edge.Cuts" user "Board Geometry/Outline")
		(27 "Margin" user)
		(31 "F.CrtYd" user "Package Geometry/Place Bound Top")
		(29 "B.CrtYd" user "Package Geometry/Place Bound Bottom")
		(35 "F.Fab" user "Ref Des/Assembly Top")
		(33 "B.Fab" user "Ref Des/Assembly Bottom")
	)
	(footprint ""
		(layer "B.Cu")
		(at 25.343866 -193.152776 -90)
		(property "Reference" "C615"
			(at 0 0 90)
			(layer "B.SilkS")
			(hide yes)
			(effects
				(font
					(size 1.27 1.27)
				)
				(justify mirror)
			)
		)
		(property "Value" ""
			(at 0 0 90)
			(layer "B.Fab")
			(effects
				(font
					(size 1.27 1.27)
				)
				(justify mirror)
			)
		)
		(duplicate_pad_numbers_are_jumpers no)
		(fp_line
			(start -0.7874 0.4064)
			(end 0.7874 0.4064)
			(stroke
				(width 0.1524)
				(type default)
			)
			(layer "B.SilkS")
		)
		(fp_line
			(start 0.7874 0.4064)
			(end 0.7874 -0.4064)
			(stroke
				(width 0.1524)
				(type default)
			)
			(layer "B.SilkS")
		)
		(fp_line
			(start -0.7874 -0.4064)
			(end -0.7874 0.4064)
			(stroke
				(width 0.1524)
				(type default)
			)
			(layer "B.SilkS")
		)
		(fp_line
			(start 0.7874 -0.4064)
			(end -0.7874 -0.4064)
			(stroke
				(width 0.1524)
				(type default)
			)
			(layer "B.SilkS")
		)
		(fp_line
			(start -0.67945 0.3048)
			(end -0.120396 0.3048)
			(stroke
				(width 0.1)
				(type default)
			)
			(layer "B.Fab")
		)
		(fp_line
			(start -0.120396 0.3048)
			(end -0.120396 0.2794)
			(stroke
				(width 0.1)
				(type default)
			)
			(layer "B.Fab")
		)
		(fp_line
			(start 0.12065 0.3048)
			(end 0.67945 0.3048)
			(stroke
				(width 0.1)
				(type default)
			)
			(layer "B.Fab")
		)
		(fp_line
			(start 0.67945 0.3048)
			(end 0.67945 -0.305054)
			(stroke
				(width 0.1)
				(type default)
			)
			(layer "B.Fab")
		)
		(fp_line
			(start -0.120396 0.2794)
			(end 0.12065 0.2794)
			(stroke
				(width 0.1)
				(type default)
			)
			(layer "B.Fab")
		)
		(fp_line
			(start 0.12065 0.2794)
			(end 0.12065 0.3048)
			(stroke
				(width 0.1)
				(type default)
			)
			(layer "B.Fab")
		)
		(fp_line
			(start -0.12065 -0.2794)
			(end -0.12065 -0.3048)
			(stroke
				(width 0.1)
				(type default)
			)
			(layer "B.Fab")
		)
		(fp_line
			(start 0.12065 -0.2794)
			(end -0.12065 -0.2794)
			(stroke
				(width 0.1)
				(type default)
			)
			(layer "B.Fab")
		)
		(fp_line
			(start -0.67945 -0.3048)
			(end -0.67945 0.3048)
			(stroke
				(width 0.1)
				(type default)
			)
			(layer "B.Fab")
		)
		(fp_line
			(start -0.12065 -0.3048)
			(end -0.67945 -0.3048)
			(stroke
				(width 0.1)
				(type default)
			)
			(layer "B.Fab")
		)
		(fp_line
			(start 0.12065 -0.305054)
			(end 0.12065 -0.2794)
			(stroke
				(width 0.1)
				(type default)
			)
			(layer "B.Fab")
		)
		(fp_line
			(start 0.67945 -0.305054)
			(end 0.12065 -0.305054)
			(stroke
				(width 0.1)
				(type default)
			)
			(layer "B.Fab")
		)
		(pad "1" smd circle
			(at 0.40005 0 90)
			(size 0 0)
			(layers "B.Cu" "B.Mask" "B.Paste")
			(net "RST_PLD_CPU1_DRAM_CD_N")
		)
		(pad "2" smd circle
			(at -0.40005 0 90)
			(size 0 0)
			(layers "B.Cu" "B.Mask" "B.Paste")
			(net "GND")
		)
	)
	(footprint ""
		(layer "B.Cu")
		(at 366.086898 -241.16665 -90)
		(property "Reference" "C381"
			(at 0 0 90)
			(layer "B.SilkS")
			(hide yes)
			(effects
				(font
					(size 1.27 1.27)
				)
				(justify mirror)
			)
		)
		(property "Value" ""
			(at 0 0 90)
			(layer "B.Fab")
			(effects
				(font
					(size 1.27 1.27)
				)
				(justify mirror)
			)
		)
		(duplicate_pad_numbers_are_jumpers no)
		(fp_line
			(start -1.524 0.762)
			(end 1.524 0.762)
			(stroke
				(width 0.1524)
				(type default)
			)
			(layer "B.SilkS")
		)
		(fp_line
			(start 1.524 0.762)
			(end 1.524 -0.762)
			(stroke
				(width 0.1524)
				(type default)
			)
			(layer "B.SilkS")
		)
		(fp_line
			(start -1.524 -0.762)
			(end -1.524 0.762)
			(stroke
				(width 0.1524)
				(type default)
			)
			(layer "B.SilkS")
		)
		(fp_line
			(start 1.524 -0.762)
			(end -1.524 -0.762)
			(stroke
				(width 0.1524)
				(type default)
			)
			(layer "B.SilkS")
		)
		(fp_line
			(start -1.1049 0.724916)
			(end -1.1049 -0.724916)
			(stroke
				(width 0.1)
				(type default)
			)
			(layer "B.Fab")
		)
		(fp_line
			(start 1.1049 0.724916)
			(end -1.1049 0.724916)
			(stroke
				(width 0.1)
				(type default)
			)
			(layer "B.Fab")
		)
		(fp_line
			(start -1.1049 -0.724916)
			(end 1.1049 -0.724916)
			(stroke
				(width 0.1)
				(type default)
			)
			(layer "B.Fab")
		)
		(fp_line
			(start 1.1049 -0.724916)
			(end 1.1049 0.724916)
			(stroke
				(width 0.1)
				(type default)
			)
			(layer "B.Fab")
		)
		(pad "1" smd rect
			(at 0.889 0 270)
			(size 1.016 1.27)
			(layers "B.Cu" "B.Mask" "B.Paste")
			(net "PVCCIN_CPU0")
		)
		(pad "2" smd rect
			(at -0.889 0 270)
			(size 1.016 1.27)
			(layers "B.Cu" "B.Mask" "B.Paste")
			(net "GND")
		)
	)
	(footprint ""
		(layer "B.Cu")
		(at 74.04608 -4.251198 90)
		(property "Reference" "R3167"
			(at 0 0 90)
			(layer "B.SilkS")
			(hide yes)
			(effects
				(font
					(size 1.27 1.27)
				)
				(justify mirror)
			)
		)
		(property "Value" ""
			(at 0 0 90)
			(layer "B.Fab")
			(effects
				(font
					(size 1.27 1.27)
				)
				(justify mirror)
			)
		)
		(duplicate_pad_numbers_are_jumpers no)
		(fp_line
			(start 0.7874 -0.4064)
			(end -0.7874 -0.4064)
			(stroke
				(width 0.1524)
				(type default)
			)
			(layer "B.SilkS")
		)
		(fp_line
			(start -0.7874 -0.4064)
			(end -0.7874 0.4064)
			(stroke
				(width 0.1524)
				(type default)
			)
			(layer "B.SilkS")
		)
		(fp_line
			(start 0.7874 0.4064)
			(end 0.7874 -0.4064)
			(stroke
				(width 0.1524)
				(type default)
			)
			(layer "B.SilkS")
		)
		(fp_line
			(start -0.7874 0.4064)
			(end 0.7874 0.4064)
			(stroke
				(width 0.1524)
				(type default)
			)
			(layer "B.SilkS")
		)
		(fp_line
			(start 0.67945 -0.305054)
			(end 0.12065 -0.305054)
			(stroke
				(width 0.1)
				(type default)
			)
			(layer "B.Fab")
		)
		(fp_line
			(start 0.12065 -0.305054)
			(end 0.12065 -0.2794)
			(stroke
				(width 0.1)
				(type default)
			)
			(layer "B.Fab")
		)
		(fp_line
			(start -0.12065 -0.3048)
			(end -0.67945 -0.3048)
			(stroke
				(width 0.1)
				(type default)
			)
			(layer "B.Fab")
		)
		(fp_line
			(start -0.67945 -0.3048)
			(end -0.67945 0.3048)
			(stroke
				(width 0.1)
				(type default)
			)
			(layer "B.Fab")
		)
		(fp_line
			(start 0.12065 -0.2794)
			(end -0.12065 -0.2794)
			(stroke
				(width 0.1)
				(type default)
			)
			(layer "B.Fab")
		)
		(fp_line
			(start -0.12065 -0.2794)
			(end -0.12065 -0.3048)
			(stroke
				(width 0.1)
				(type default)
			)
			(layer "B.Fab")
		)
		(fp_line
			(start 0.12065 0.2794)
			(end 0.12065 0.3048)
			(stroke
				(width 0.1)
				(type default)
			)
			(layer "B.Fab")
		)
		(fp_line
			(start -0.120396 0.2794)
			(end 0.12065 0.2794)
			(stroke
				(width 0.1)
				(type default)
			)
			(layer "B.Fab")
		)
		(fp_line
			(start 0.67945 0.3048)
			(end 0.67945 -0.305054)
			(stroke
				(width 0.1)
				(type default)
			)
			(layer "B.Fab")
		)
		(fp_line
			(start 0.12065 0.3048)
			(end 0.67945 0.3048)
			(stroke
				(width 0.1)
				(type default)
			)
			(layer "B.Fab")
		)
		(fp_line
			(start -0.120396 0.3048)
			(end -0.120396 0.2794)
			(stroke
				(width 0.1)
				(type default)
			)
			(layer "B.Fab")
		)
		(fp_line
			(start -0.67945 0.3048)
			(end -0.120396 0.3048)
			(stroke
				(width 0.1)
				(type default)
			)
			(layer "B.Fab")
		)
		(pad "1" smd circle
			(at 0.40005 0 270)
			(size 0 0)
			(layers "B.Cu" "B.Mask" "B.Paste")
			(net "OCP_V3_2_ID1")
		)
		(pad "2" smd circle
			(at -0.40005 0 270)
			(size 0 0)
			(layers "B.Cu" "B.Mask" "B.Paste")
			(net "GND")
		)
	)
	(footprint ""
		(layer "B.Cu")
		(at 369.49888 -42.128948 180)
		(property "Reference" "R4110"
			(at 0 0 0)
			(layer "B.SilkS")
			(hide yes)
			(effects
				(font
					(size 1.27 1.27)
				)
				(justify mirror)
			)
		)
		(property "Value" ""
			(at 0 0 0)
			(layer "B.Fab")
			(effects
				(font
					(size 1.27 1.27)
				)
				(justify mirror)
			)
		)
		(duplicate_pad_numbers_are_jumpers no)
		(fp_line
			(start 0.7874 0.4064)
			(end 0.7874 -0.4064)
			(stroke
				(width 0.1524)
				(type default)
			)
			(layer "B.SilkS")
		)
		(fp_line
			(start 0.7874 -0.4064)
			(end -0.7874 -0.4064)
			(stroke
				(width 0.1524)
				(type default)
			)
			(layer "B.SilkS")
		)
		(fp_line
			(start -0.7874 0.4064)
			(end 0.7874 0.4064)
			(stroke
				(width 0.1524)
				(type default)
			)
			(layer "B.SilkS")
		)
		(fp_line
			(start -0.7874 -0.4064)
			(end -0.7874 0.4064)
			(stroke
				(width 0.1524)
				(type default)
			)
			(layer "B.SilkS")
		)
		(fp_line
			(start 0.67945 0.3048)
			(end 0.67945 -0.305054)
			(stroke
				(width 0.1)
				(type default)
			)
			(layer "B.Fab")
		)
		(fp_line
			(start 0.67945 -0.305054)
			(end 0.12065 -0.305054)
			(stroke
				(width 0.1)
				(type default)
			)
			(layer "B.Fab")
		)
		(fp_line
			(start 0.12065 0.3048)
			(end 0.67945 0.3048)
			(stroke
				(width 0.1)
				(type default)
			)
			(layer "B.Fab")
		)
		(fp_line
			(start 0.12065 0.2794)
			(end 0.12065 0.3048)
			(stroke
				(width 0.1)
				(type default)
			)
			(layer "B.Fab")
		)
		(fp_line
			(start 0.12065 -0.2794)
			(end -0.12065 -0.2794)
			(stroke
				(width 0.1)
				(type default)
			)
			(layer "B.Fab")
		)
		(fp_line
			(start 0.12065 -0.305054)
			(end 0.12065 -0.2794)
			(stroke
				(width 0.1)
				(type default)
			)
			(layer "B.Fab")
		)
		(fp_line
			(start -0.120396 0.3048)
			(end -0.120396 0.2794)
			(stroke
				(width 0.1)
				(type default)
			)
			(layer "B.Fab")
		)
		(fp_line
			(start -0.120396 0.2794)
			(end 0.12065 0.2794)
			(stroke
				(width 0.1)
				(type default)
			)
			(layer "B.Fab")
		)
		(fp_line
			(start -0.12065 -0.2794)
			(end -0.12065 -0.3048)
			(stroke
				(width 0.1)
				(type default)
			)
			(layer "B.Fab")
		)
		(fp_line
			(start -0.12065 -0.3048)
			(end -0.67945 -0.3048)
			(stroke
				(width 0.1)
				(type default)
			)
			(layer "B.Fab")
		)
		(fp_line
			(start -0.67945 0.3048)
			(end -0.120396 0.3048)
			(stroke
				(width 0.1)
				(type default)
			)
			(layer "B.Fab")
		)
		(fp_line
			(start -0.67945 -0.3048)
			(end -0.67945 0.3048)
			(stroke
				(width 0.1)
				(type default)
			)
			(layer "B.Fab")
		)
		(pad "1" smd circle
			(at 0.40005 0)
			(size 0 0)
			(layers "B.Cu" "B.Mask" "B.Paste")
			(net "PD_PCH_GPP_E_14")
		)
		(pad "2" smd circle
			(at -0.40005 0)
			(size 0 0)
			(layers "B.Cu" "B.Mask" "B.Paste")
			(net "GND")
		)
	)
	(footprint ""
		(layer "B.Cu")
		(at 236.982254 -134.048754)
		(property "Reference" "R1017"
			(at 0 0 0)
			(layer "B.SilkS")
			(hide yes)
			(effects
				(font
					(size 1.27 1.27)
				)
				(justify mirror)
			)
		)
		(property "Value" ""
			(at 0 0 0)
			(layer "B.Fab")
			(effects
				(font
					(size 1.27 1.27)
				)
				(justify mirror)
			)
		)
		(duplicate_pad_numbers_are_jumpers no)
		(fp_line
			(start -0.7874 -0.4064)
			(end -0.7874 0.4064)
			(stroke
				(width 0.1524)
				(type default)
			)
			(layer "B.SilkS")
		)
		(fp_line
			(start -0.7874 0.4064)
			(end 0.7874 0.4064)
			(stroke
				(width 0.1524)
				(type default)
			)
			(layer "B.SilkS")
		)
		(fp_line
			(start -0.559054 -0.4064)
			(end -0.7874 -0.4064)
			(stroke
				(width 0.1524)
				(type default)
			)
			(layer "B.SilkS")
		)
		(fp_line
			(start 0.7874 -0.4064)
			(end -0.223774 -0.4064)
			(stroke
				(width 0.1524)
				(type default)
			)
			(layer "B.SilkS")
		)
		(fp_line
			(start 0.7874 -0.226314)
			(end 0.7874 -0.4064)
			(stroke
				(width 0.1524)
				(type default)
			)
			(layer "B.SilkS")
		)
		(fp_line
			(start 0.7874 0.4064)
			(end 0.7874 0.253746)
			(stroke
				(width 0.1524)
				(type default)
			)
			(layer "B.SilkS")
		)
		(fp_line
			(start -0.67945 -0.3048)
			(end -0.67945 0.3048)
			(stroke
				(width 0.1)
				(type default)
			)
			(layer "B.Fab")
		)
		(fp_line
			(start -0.67945 0.3048)
			(end -0.120396 0.3048)
			(stroke
				(width 0.1)
				(type default)
			)
			(layer "B.Fab")
		)
		(fp_line
			(start -0.12065 -0.3048)
			(end -0.67945 -0.3048)
			(stroke
				(width 0.1)
				(type default)
			)
			(layer "B.Fab")
		)
		(fp_line
			(start -0.12065 -0.2794)
			(end -0.12065 -0.3048)
			(stroke
				(width 0.1)
				(type default)
			)
			(layer "B.Fab")
		)
		(fp_line
			(start -0.120396 0.2794)
			(end 0.12065 0.2794)
			(stroke
				(width 0.1)
				(type default)
			)
			(layer "B.Fab")
		)
		(fp_line
			(start -0.120396 0.3048)
			(end -0.120396 0.2794)
			(stroke
				(width 0.1)
				(type default)
			)
			(layer "B.Fab")
		)
		(fp_line
			(start 0.12065 -0.305054)
			(end 0.12065 -0.2794)
			(stroke
				(width 0.1)
				(type default)
			)
			(layer "B.Fab")
		)
		(fp_line
			(start 0.12065 -0.2794)
			(end -0.12065 -0.2794)
			(stroke
				(width 0.1)
				(type default)
			)
			(layer "B.Fab")
		)
		(fp_line
			(start 0.12065 0.2794)
			(end 0.12065 0.3048)
			(stroke
				(width 0.1)
				(type default)
			)
			(layer "B.Fab")
		)
		(fp_line
			(start 0.12065 0.3048)
			(end 0.67945 0.3048)
			(stroke
				(width 0.1)
				(type default)
			)
			(layer "B.Fab")
		)
		(fp_line
			(start 0.67945 -0.305054)
			(end 0.12065 -0.305054)
			(stroke
				(width 0.1)
				(type default)
			)
			(layer "B.Fab")
		)
		(fp_line
			(start 0.67945 0.3048)
			(end 0.67945 -0.305054)
			(stroke
				(width 0.1)
				(type default)
			)
			(layer "B.Fab")
		)
		(pad "1" smd rect
			(at 0.40005 0)
			(size 0.4572 0.508)
			(layers "B.Cu" "B.Mask" "B.Paste")
			(net "CLK_25M_PCH_CPU1_DP")
		)
		(pad "2" smd rect
			(at -0.40005 0)
			(size 0.4572 0.508)
			(layers "B.Cu" "B.Mask" "B.Paste")
			(net "CLK_25M_NSSC_CPU1_DP")
		)
	)
	(footprint ""
		(layer "B.Cu")
		(at 422.314624 -193.353436 -90)
		(property "Reference" "R838"
			(at 0 0 90)
			(layer "B.SilkS")
			(hide yes)
			(effects
				(font
					(size 1.27 1.27)
				)
				(justify mirror)
			)
		)
		(property "Value" ""
			(at 0 0 90)
			(layer "B.Fab")
			(effects
				(font
					(size 1.27 1.27)
				)
				(justify mirror)
			)
		)
		(duplicate_pad_numbers_are_jumpers no)
		(fp_line
			(start -0.7874 0.4064)
			(end 0.7874 0.4064)
			(stroke
				(width 0.1524)
				(type default)
			)
			(layer "B.SilkS")
		)
		(fp_line
			(start 0.7874 0.4064)
			(end 0.7874 -0.4064)
			(stroke
				(width 0.1524)
				(type default)
			)
			(layer "B.SilkS")
		)
		(fp_line
			(start -0.7874 -0.4064)
			(end -0.7874 0.4064)
			(stroke
				(width 0.1524)
				(type default)
			)
			(layer "B.SilkS")
		)
		(fp_line
			(start 0.7874 -0.4064)
			(end -0.7874 -0.4064)
			(stroke
				(width 0.1524)
				(type default)
			)
			(layer "B.SilkS")
		)
		(fp_line
			(start -0.67945 0.3048)
			(end -0.120396 0.3048)
			(stroke
				(width 0.1)
				(type default)
			)
			(layer "B.Fab")
		)
		(fp_line
			(start -0.120396 0.3048)
			(end -0.120396 0.2794)
			(stroke
				(width 0.1)
				(type default)
			)
			(layer "B.Fab")
		)
		(fp_line
			(start 0.12065 0.3048)
			(end 0.67945 0.3048)
			(stroke
				(width 0.1)
				(type default)
			)
			(layer "B.Fab")
		)
		(fp_line
			(start 0.67945 0.3048)
			(end 0.67945 -0.305054)
			(stroke
				(width 0.1)
				(type default)
			)
			(layer "B.Fab")
		)
		(fp_line
			(start -0.120396 0.2794)
			(end 0.12065 0.2794)
			(stroke
				(width 0.1)
				(type default)
			)
			(layer "B.Fab")
		)
		(fp_line
			(start 0.12065 0.2794)
			(end 0.12065 0.3048)
			(stroke
				(width 0.1)
				(type default)
			)
			(layer "B.Fab")
		)
		(fp_line
			(start -0.12065 -0.2794)
			(end -0.12065 -0.3048)
			(stroke
				(width 0.1)
				(type default)
			)
			(layer "B.Fab")
		)
		(fp_line
			(start 0.12065 -0.2794)
			(end -0.12065 -0.2794)
			(stroke
				(width 0.1)
				(type default)
			)
			(layer "B.Fab")
		)
		(fp_line
			(start -0.67945 -0.3048)
			(end -0.67945 0.3048)
			(stroke
				(width 0.1)
				(type default)
			)
			(layer "B.Fab")
		)
		(fp_line
			(start -0.12065 -0.3048)
			(end -0.67945 -0.3048)
			(stroke
				(width 0.1)
				(type default)
			)
			(layer "B.Fab")
		)
		(fp_line
			(start 0.12065 -0.305054)
			(end 0.12065 -0.2794)
			(stroke
				(width 0.1)
				(type default)
			)
			(layer "B.Fab")
		)
		(fp_line
			(start 0.67945 -0.305054)
			(end 0.12065 -0.305054)
			(stroke
				(width 0.1)
				(type default)
			)
			(layer "B.Fab")
		)
		(pad "1" smd circle
			(at 0.40005 0 90)
			(size 0 0)
			(layers "B.Cu" "B.Mask" "B.Paste")
			(net "RST_PLD_CPU0_DRAM_EF_N")
		)
		(pad "2" smd circle
			(at -0.40005 0 90)
			(size 0 0)
			(layers "B.Cu" "B.Mask" "B.Paste")
			(net "RST_M_EF_CPU0_FPGA_N")
		)
	)
)
